(kicad_pcb
	(version 20260206)
	(generator "pcbnew")
	(generator_version "10.0")
	(general
		(thickness 1.6)
		(legacy_teardrops no)
	)
	(paper "A4")
	(title_block
		(title "Bryce Canyon_IOM_IOC_16318-2_OCP.brd")
		(comment 1 "Bryce Canyon / footprints 778-779 of 1605")
	)
	(layers
		(0 "F.Cu" signal "TOP")
		(4 "In1.Cu" signal "L2GND")
		(6 "In2.Cu" signal "L3")
		(8 "In3.Cu" signal "L4VCC")
		(10 "In4.Cu" signal "L5VCC")
		(12 "In5.Cu" signal "L6")
		(14 "In6.Cu" signal "L7GND")
		(2 "B.Cu" signal "BOTTOM")
		(9 "F.Adhes" user "F.Adhesive")
		(11 "B.Adhes" user "B.Adhesive")
		(13 "F.Paste" user "Package Geometry/Pastemask Top")
		(15 "B.Paste" user "Package Geometry/Pastemask Bottom")
		(5 "F.SilkS" user "Ref Des/Silkscreen Top")
		(7 "B.SilkS" user "Ref Des/Silkscreen Bottom")
		(1 "F.Mask" user "Board Geometry/Soldermask Top")
		(3 "B.Mask" user "Board Geometry/Soldermask Bottom")
		(17 "Dwgs.User" user "User.Drawings")
		(19 "Cmts.User" user "User.Comments")
		(21 "Eco1.User" user "User.Eco1")
		(23 "Eco2.User" user "User.Eco2")
		(25 "Edge.Cuts" user "Board Geometry/Outline")
		(27 "Margin" user)
		(31 "F.CrtYd" user "Package Geometry/Place Bound Top")
		(29 "B.CrtYd" user "Package Geometry/Place Bound Bottom")
		(35 "F.Fab" user "Ref Des/Assembly Top")
		(33 "B.Fab" user "Ref Des/Assembly Bottom")
	)
	(footprint ""
		(layer "F.Cu")
		(at 142.494 -20.828 -90)
		(property "Reference" "R735"
			(at 0 0 270)
			(layer "F.SilkS")
			(hide yes)
			(effects
				(font
					(size 1.27 1.27)
				)
			)
		)
		(property "Value" "1KR2F-3-GP"
			(at 0.064008 -3.993896 270)
			(unlocked yes)
			(layer "F.Fab")
			(hide yes)
			(effects
				(font
					(size 1.016 1.016)
					(thickness 0.1524)
				)
			)
		)
		(property "Device Type" "R402H16"
			(at 0.064008 -5.517896 270)
			(unlocked yes)
			(layer "F.Fab")
			(hide yes)
			(effects
				(font
					(size 1.016 1.016)
					(thickness 0.1524)
				)
			)
		)
		(duplicate_pad_numbers_are_jumpers no)
		(fp_line
			(start -0.508 -0.9398)
			(end -0.508 0.9398)
			(stroke
				(width 0.1524)
				(type default)
			)
			(layer "F.SilkS")
		)
		(fp_line
			(start 0.508 -0.9398)
			(end -0.508 -0.9398)
			(stroke
				(width 0.1524)
				(type default)
			)
			(layer "F.SilkS")
		)
		(fp_rect
			(start -0.508 0.9398)
			(end 0.508 -0.9398)
			(stroke
				(width 0)
				(type default)
			)
			(fill no)
			(layer "F.CrtYd")
		)
		(fp_rect
			(start -0.508 0.9398)
			(end 0.508 -0.9398)
			(stroke
				(width 0)
				(type default)
			)
			(fill no)
			(layer "F.Fab")
		)
		(pad "1" smd custom
			(at 0 -0.4445 270)
			(size 0.1397 0.1397)
			(layers "F.Cu" "F.Mask" "F.Paste")
			(net "P3V3_STBY")
			(options
				(clearance outline)
				(anchor circle)
			)
			(primitives
				(gr_poly
					(pts
						(arc
							(start -0.1778 -0.2794)
							(mid -0.249642 -0.249642)
							(end -0.2794 -0.1778)
						)
						(arc
							(start -0.2794 0.1778)
							(mid -0.249642 0.249642)
							(end -0.1778 0.2794)
						)
						(arc
							(start 0.1778 0.2794)
							(mid 0.249642 0.249642)
							(end 0.2794 0.1778)
						)
						(arc
							(start 0.2794 -0.1778)
							(mid 0.249642 -0.249642)
							(end 0.1778 -0.2794)
						)
					)
					(width 0)
					(fill yes)
				)
			)
		)
		(pad "2" smd custom
			(at 0 0.4445 270)
			(size 0.1397 0.1397)
			(layers "F.Cu" "F.Mask" "F.Paste")
			(net "EXT2_LED_YELLOW_D")
			(options
				(clearance outline)
				(anchor circle)
			)
			(primitives
				(gr_poly
					(pts
						(arc
							(start -0.1778 -0.2794)
							(mid -0.249642 -0.249642)
							(end -0.2794 -0.1778)
						)
						(arc
							(start -0.2794 0.1778)
							(mid -0.249642 0.249642)
							(end -0.1778 0.2794)
						)
						(arc
							(start 0.1778 0.2794)
							(mid 0.249642 0.249642)
							(end 0.2794 0.1778)
						)
						(arc
							(start 0.2794 -0.1778)
							(mid 0.249642 -0.249642)
							(end 0.1778 -0.2794)
						)
					)
					(width 0)
					(fill yes)
				)
			)
		)
	)
	(footprint ""
		(layer "F.Cu")
		(at 62.8396 -162.8648)
		(property "Reference" "C50"
			(at 0 0 0)
			(layer "F.SilkS")
			(hide yes)
			(effects
				(font
					(size 1.27 1.27)
				)
			)
		)
		(property "Value" "SCD1U16V2KX-3GP"
			(at 1.1811 -2.7051 0)
			(unlocked yes)
			(layer "F.Fab")
			(hide yes)
			(effects
				(font
					(size 1.016 1.016)
					(thickness 0.1524)
				)
			)
		)
		(property "Device Type" "C402H22"
			(at 1.1811 -4.2291 0)
			(unlocked yes)
			(layer "F.Fab")
			(hide yes)
			(effects
				(font
					(size 1.016 1.016)
					(thickness 0.1524)
				)
			)
		)
		(duplicate_pad_numbers_are_jumpers no)
		(fp_rect
			(start -0.4318 0.9525)
			(end 0.4318 -0.9525)
			(stroke
				(width 0)
				(type default)
			)
			(fill no)
			(layer "F.CrtYd")
		)
		(fp_rect
			(start -0.4318 0.9525)
			(end 0.4318 -0.9525)
			(stroke
				(width 0)
				(type default)
			)
			(fill no)
			(layer "F.Fab")
		)
		(pad "1" smd custom
			(at 0 -0.4445)
			(size 0.1524 0.1524)
			(layers "F.Cu" "F.Mask" "F.Paste")
			(net "FM_TPM_PRSNT_RST")
			(options
				(clearance outline)
				(anchor circle)
			)
			(primitives
				(gr_poly
					(pts
						(arc
							(start 0.3048 -0.2032)
							(mid 0.275042 -0.275042)
							(end 0.2032 -0.3048)
						)
						(arc
							(start -0.2032 -0.3048)
							(mid -0.275042 -0.275042)
							(end -0.3048 -0.2032)
						)
						(arc
							(start -0.3048 0.2032)
							(mid -0.275042 0.275042)
							(end -0.2032 0.3048)
						)
						(arc
							(start 0.2032 0.3048)
							(mid 0.275042 0.275042)
							(end 0.3048 0.2032)
						)
					)
					(width 0)
					(fill yes)
				)
			)
		)
		(pad "2" smd custom
			(at 0 0.4445)
			(size 0.1524 0.1524)
			(layers "F.Cu" "F.Mask" "F.Paste")
			(net "GND")
			(options
				(clearance outline)
				(anchor circle)
			)
			(primitives
				(gr_poly
					(pts
						(arc
							(start 0.3048 -0.2032)
							(mid 0.275042 -0.275042)
							(end 0.2032 -0.3048)
						)
						(arc
							(start -0.2032 -0.3048)
							(mid -0.275042 -0.275042)
							(end -0.3048 -0.2032)
						)
						(arc
							(start -0.3048 0.2032)
							(mid -0.275042 0.275042)
							(end -0.2032 0.3048)
						)
						(arc
							(start 0.2032 0.3048)
							(mid 0.275042 0.275042)
							(end 0.3048 0.2032)
						)
					)
					(width 0)
					(fill yes)
				)
			)
		)
	)
)
